FILE_TYPE = CONNECTIVITY;
{Allegro Design Entry HDL 17.2-2016 S081 (4005846) 1/11/2022}
"PAGE_NUMBER" = 173;
0"NC";
1"GND\g";
2"GND\g";
3"GND\g";
4"GND\g";
5"GND\g";
6"GND\g";
7"GND\g";
8"GND\g";
9"GND\g";
10"GND\g";
11"PVDDCR_SOC_P0\g";
12"SW_P12V_STBY_PVDDCR_SOC_P0_FLT\g";
13"NC_PVDDCR_SOC_P0_DNC2";
14"SW_PVDDCR_SOC_P0_PH2";
15"SW_PVDDCR_SOC_P0_SW2";
16"GND\g";
17"SW_PVDDCR_SOC_P0_BOOT1";
18"SW_PVDDCR_SOC_P0_SW1";
19"SW_PVDDCR_SOC_P0_PH1";
20"GND\g";
21"P12V_STBY\g";
22"GND\g";
23"SW_PVDDCR_SOC_P0_BOOT1_RC";
24"IND_SOC_P0_CPL2";
25"PVDDCR_SOC_P0\g";
26"GND\g";
27"IND_SOC_P0_CPL2";
28"IND_SOC_P0_CPL3";
29"PVDDCR_SOC_P0_TEMP1";
30"PVDDCR_SOC_P0_IMON1";
31"PVDDCR_SOC_P0_PWM1";
32"NC_PVDDCR_SOC_P0_DNC1";
33"PVDDCR_SOC_P0_LSET1";
34"PVDDCR_CPU0_P0_VCCS";
35"PVDDCR_CPU0_P0_PVCC\g";
36"SW_PVDDCR_SOC_P0_BOOT2";
37"SW_PVDDCR_SOC_P0_SW2_RC";
38"NC_PVDDCR_SOC_P0_GL1_2";
39"NC_PVDDCR_SOC_P0_GL2_2";
40"GND\g";
41"PVDDCR_SOC_P0_VCC2";
42"PVDDCR_SOC_P0_IMON2";
43"PVDDCR_SOC_P0_TEMP1";
44"PVDDCR_SOC_P0_PWM2";
45"PVDDCR_SOC_P0_LSET2";
46"PVDDCR_CPU0_P0_VCCS";
47"PVDDCR_CPU0_P0_PVCC\g";
48"GND\g";
49"NC_PVDDCR_SOC_P0_GL2_1";
50"SW_P12V_STBY_PVDDCR_SOC_P0_FLT\g";
51"SW_PVDDCR_SOC_P0_BOOT2_RC";
52"SW_PVDDCR_SOC_P0_SW1_RC";
53"NC_PVDDCR_SOC_P0_GL1_1";
54"PVDDCR_SOC_P0_VCC1";
55"PVDDCR_SOC_P0_VOS1";
56"GND\g";
57"PVDDCR_SOC_P0_VOS2";
58"PVDDCR_SOC_P0\g";
59"GND\g";
%"VCC_CORE"
"1","(-3875,6025)","0","pure_quanta_power","I102";
;
HDL_POWER"SW_P12V_STBY_PVDDCR_SOC_P0_FLT"
CDS_LIB"pure_quanta_power";
"A"50;
%"VCC_CORE"
"1","(-1150,3350)","0","pure_quanta_power","I104";
;
HDL_POWER"PVDDCR_SOC_P0"
CDS_LIB"pure_quanta_power";
"A"25;
%"UNIVERSAL_GND"
"1","(-1150,2725)","0","pure_quanta_power","I105";
;
CDS_LIB"pure_quanta_power"
HDL_POWER"GND";
"A"59;
%"Q_CAPP"
"1","(-3425,5750)","0","pure_quanta","I106";
;
LOCATION"PC596"
$SEC"1"
CDS_SEC"1"
PART_NUMBER"CC72204MD02"
MATERIAL"OSCON"
TOLERANCE"20%"
VALUE"220UF"
VOLTAGE"25V"
PACK_TYPE"THLF"
CDS_LIB"pure_quanta";
"A"
$PN"1"50;
"B"
$PN"2"16;
%"Q_CAPP"
"1","(-1150,3075)","0","pure_quanta","I107";
;
LOCATION"PC601"
$SEC"1"
CDS_SEC"1"
MATERIAL"SPCAP"
TOLERANCE"20%"
VALUE"470UF"
PART_NUMBER"CH747LM8825"
VOLTAGE"2.5V"
PACK_TYPE"SMLF"
CDS_LIB"pure_quanta";
"A"
$PN"1"25;
"B"
$PN"2"59;
%"Q_CAP"
"1","(-5425,5750)","0","pure_quanta","I108";
;
LOCATION"PC583_1"
$SEC"1"
CDS_SEC"1"
MATERIAL"X7R"
TOLERANCE"10%"
VALUE"0.1UF"
VOLTAGE"25V"
PART_NUMBER"CH4104K1B00"
PACK_TYPE"0402"
CDS_LIB"pure_quanta";
"B"
$PN"2"16;
"A"
$PN"1"50;
%"Q_CAP"
"1","(-5350,2700)","0","pure_quanta","I109";
;
LOCATION"PC584_2"
$SEC"1"
CDS_SEC"1"
MATERIAL"X7R"
TOLERANCE"10%"
VALUE"0.1UF"
VOLTAGE"25V"
PACK_TYPE"0402"
PART_NUMBER"CH4104K1B00"
CDS_LIB"pure_quanta";
"B"
$PN"2"56;
"A"
$PN"1"12;
%"Q_CAP"
"1","(-7525,5250)","0","pure_quanta","I110";
;
LOCATION"PC579"
$SEC"1"
CDS_SEC"1"
MATERIAL"X6S"
TOLERANCE"10%"
VALUE"2.2UF"
PART_NUMBER"CH5222KEB01"
VOLTAGE"10V"
PACK_TYPE"C0402"
CDS_LIB"pure_quanta";
"B"
$PN"2"1;
"A"
$PN"1"54;
%"UNIVERSAL_GND"
"1","(-7525,5050)","0","pure_quanta_power","I111";
;
CDS_LIB"pure_quanta_power"
HDL_POWER"GND";
"A"1;
%"UNIVERSAL_GND"
"1","(-7175,5500)","0","pure_quanta_power","I112";
;
CDS_LIB"pure_quanta_power"
HDL_POWER"GND";
"A"2;
%"Q_RES"
"2","(-7525,5750)","0","pure_quanta","I113";
;
LOCATION"PR356"
$SEC"1"
CDS_SEC"1"
WATTAGE"1/16W"
MATERIAL"CHIP"
TOLERANCE"1%"
VALUE"2.2"
PART_NUMBER"CS-2202FB00"
PACK_TYPE"0402LF"
CDS_LIB"pure_quanta";
"A"
$PN"1"35;
"B"
$PN"2"54;
%"Q_CAP"
"1","(-7175,5750)","0","pure_quanta","I114";
;
LOCATION"PC581_SOP0_1"
$SEC"1"
CDS_SEC"1"
MATERIAL"X6S"
TOLERANCE"10%"
VALUE"2.2UF"
PART_NUMBER"CH5222KEB01"
VOLTAGE"10V"
PACK_TYPE"C0402"
CDS_LIB"pure_quanta";
"B"
$PN"2"2;
"A"
$PN"1"35;
%"Q_CAP"
"1","(-7500,2150)","0","pure_quanta","I116";
;
LOCATION"PC580"
$SEC"1"
CDS_SEC"1"
MATERIAL"X6S"
TOLERANCE"10%"
VALUE"2.2UF"
PART_NUMBER"CH5222KEB01"
VOLTAGE"10V"
PACK_TYPE"C0402"
CDS_LIB"pure_quanta";
"B"
$PN"2"3;
"A"
$PN"1"41;
%"UNIVERSAL_GND"
"1","(-7500,1950)","0","pure_quanta_power","I117";
;
CDS_LIB"pure_quanta_power"
HDL_POWER"GND";
"A"3;
%"UNIVERSAL_GND"
"1","(-7150,2425)","0","pure_quanta_power","I118";
;
CDS_LIB"pure_quanta_power"
HDL_POWER"GND";
"A"4;
%"Q_RES"
"2","(-7500,2675)","0","pure_quanta","I119";
;
LOCATION"PR357"
$SEC"1"
CDS_SEC"1"
WATTAGE"1/16W"
MATERIAL"CHIP"
TOLERANCE"1%"
VALUE"2.2"
PART_NUMBER"CS-2202FB00"
PACK_TYPE"0402LF"
CDS_LIB"pure_quanta";
"A"
$PN"1"47;
"B"
$PN"2"41;
%"Q_CAP"
"1","(-7150,2675)","0","pure_quanta","I120";
;
LOCATION"PC582_SOP0_2"
$SEC"1"
CDS_SEC"1"
VALUE"2.2UF"
MATERIAL"X6S"
TOLERANCE"10%"
PART_NUMBER"CH5222KEB01"
VOLTAGE"10V"
PACK_TYPE"C0402"
CDS_LIB"pure_quanta";
"B"
$PN"2"4;
"A"
$PN"1"47;
%"ISL99390FRZTR5935"
"1","(-6025,4900)","0","pure_quanta","I122";
;
LOCATION"PU49"
$SEC"1"
CDS_SEC"1"
PART_TYPE"SMLF"
MATERIAL"IC"
VALUE"ISL99390FRZ-TR5935"
PART_NUMBER"AL099390004"
CDS_LMAN_SYM_OUTLINE"-300,700,250,-650"
NEEDS_NO_SIZE"TRUE"
CDS_LIB"pure_quanta";
"PGND2"
$PN"7_9-20_24"48;
"GL2"
$PN"41"49;
"GL1"
$PN"6"53;
"DNC"
$PN"31"32;
"EN"
$PN"35"54;
"PGND3"
$PN"40"48;
"VOS"
$PN"1"55;
"VIN2"
$PN"30"50;
"PGND1"
$PN"5"48;
"SW"
$PN"10_19"18;
"LSET"
$PN"37"33;
"IOUT"
$PN"38"30;
"TOUT_FLT"
$PN"36"29;
"PVCC"
$PN"4"35;
"PHASE"
$PN"32"19;
"VIN1"
$PN"25_29"50;
"BOOT"
$PN"33"17;
"AGND"
$PN"2"48;
"VCC"
$PN"3"54;
"REFIN"
$PN"39"34;
"PWM"
$PN"34"31;
%"ISL99390FRZTR5935"
"1","(-6000,1800)","0","pure_quanta","I123";
;
LOCATION"PU50"
$SEC"1"
CDS_SEC"1"
PART_TYPE"SMLF"
MATERIAL"IC"
VALUE"ISL99390FRZ-TR5935"
PART_NUMBER"AL099390004"
CDS_LMAN_SYM_OUTLINE"-300,700,250,-650"
NEEDS_NO_SIZE"TRUE"
CDS_LIB"pure_quanta";
"PGND2"
$PN"7_9-20_24"40;
"GL2"
$PN"41"39;
"GL1"
$PN"6"38;
"DNC"
$PN"31"13;
"EN"
$PN"35"41;
"PGND3"
$PN"40"40;
"VOS"
$PN"1"57;
"VIN2"
$PN"30"12;
"PGND1"
$PN"5"40;
"SW"
$PN"10_19"15;
"LSET"
$PN"37"45;
"IOUT"
$PN"38"42;
"TOUT_FLT"
$PN"36"43;
"PVCC"
$PN"4"47;
"PHASE"
$PN"32"14;
"VIN1"
$PN"25_29"12;
"BOOT"
$PN"33"36;
"AGND"
$PN"2"40;
"VCC"
$PN"3"41;
"REFIN"
$PN"39"46;
"PWM"
$PN"34"44;
%"Q_CAP"
"1","(-4675,4650)","0","pure_quanta","I125";
;
LOCATION"PC185"
$SEC"1"
CDS_SEC"1"
PART_NUMBER"CH1566K1B09"
TOLERANCE"10%"
MATERIAL"EMPTY"
PACK_TYPE"C0402"
VALUE"560PF"
VOLTAGE"50V"
CDS_LIB"pure_quanta";
"B"
$PN"2"52;
"A"
$PN"1"18;
%"Q_RES"
"2","(-4675,4200)","0","pure_quanta","I126";
;
LOCATION"PR502"
$SEC"1"
CDS_SEC"1"
WATTAGE"1/8W"
MATERIAL"EMPTY"
TOLERANCE"1%"
VALUE"1.5"
PART_NUMBER"CS-1504FB00"
PACK_TYPE"0402LF"
CDS_LIB"pure_quanta";
"A"
$PN"1"52;
"B"
$PN"2"5;
%"UNIVERSAL_GND"
"1","(-4675,3950)","0","pure_quanta_power","I127";
;
CDS_LIB"pure_quanta_power"
HDL_POWER"GND";
"A"5;
%"Q_CAP"
"1","(-4700,1625)","0","pure_quanta","I128";
;
LOCATION"PC187"
$SEC"1"
CDS_SEC"1"
MATERIAL"EMPTY"
TOLERANCE"10%"
VALUE"560PF"
PART_NUMBER"CH1566K1B09"
VOLTAGE"50V"
PACK_TYPE"C0402"
CDS_LIB"pure_quanta";
"B"
$PN"2"37;
"A"
$PN"1"15;
%"Q_RES"
"2","(-4700,1125)","0","pure_quanta","I129";
;
LOCATION"PR503"
$SEC"1"
CDS_SEC"1"
WATTAGE"1/8W"
MATERIAL"EMPTY"
TOLERANCE"1%"
VALUE"1.5"
PART_NUMBER"CS-1504FB00"
PACK_TYPE"0402LF"
CDS_LIB"pure_quanta";
"A"
$PN"1"37;
"B"
$PN"2"6;
%"UNIVERSAL_GND"
"1","(-4700,900)","0","pure_quanta_power","I130";
;
CDS_LIB"pure_quanta_power"
HDL_POWER"GND";
"A"6;
%"VCC_CORE"
"1","(-7525,6150)","0","pure_quanta_power","I131";
;
HDL_POWER"PVDDCR_CPU0_P0_PVCC"
CDS_LIB"pure_quanta_power";
"A"35;
%"VCC_CORE"
"1","(-7500,3075)","0","pure_quanta_power","I132";
;
HDL_POWER"PVDDCR_CPU0_P0_PVCC"
CDS_LIB"pure_quanta_power";
"A"47;
%"Q_RES"
"2","(-550,4700)","0","pure_quanta","I133";
;
LOCATION"PR334"
$SEC"1"
CDS_SEC"1"
WATTAGE"1/16W"
MATERIAL"CHIP"
TOLERANCE"1%"
VALUE"1K"
PART_NUMBER"TMP_QCS21002FB24"
PACK_TYPE"0402LF"
CDS_LIB"pure_quanta";
"A"
$PN"1"11;
"B"
$PN"2"20;
%"Q_CAP"
"1","(-3800,5750)","0","pure_quanta","I134";
;
LOCATION"PC593_1"
$SEC"1"
CDS_SEC"1"
MATERIAL"X6S"
TOLERANCE"10%"
VALUE"10UF"
PART_NUMBER"CH6104KEA00"
VOLTAGE"25V"
PACK_TYPE"C0805"
CDS_LIB"pure_quanta";
"B"
$PN"2"16;
"A"
$PN"1"50;
%"Q_CAP"
"1","(-3600,2700)","0","pure_quanta","I135";
;
LOCATION"PC595_2"
$SEC"1"
CDS_SEC"1"
MATERIAL"X6S"
TOLERANCE"10%"
VALUE"10UF"
PART_NUMBER"CH6104KEA00"
VOLTAGE"25V"
PACK_TYPE"C0805"
CDS_LIB"pure_quanta";
"B"
$PN"2"56;
"A"
$PN"1"12;
%"UNIVERSAL_GND"
"1","(-2225,4500)","0","pure_quanta_power","I137";
;
CDS_LIB"pure_quanta_power"
HDL_POWER"GND";
"A"22;
%"Q_RES"
"1","(-7200,4600)","0","pure_quanta","I15";
;
LOCATION"PR358"
$SEC"1"
CDS_SEC"1"
WATTAGE"1/16W"
MATERIAL"EMPTY"
TOLERANCE"1%"
VALUE"8.87K"
PART_NUMBER"CS28872FB01"
PACK_TYPE"0402LF"
CDS_LIB"pure_quanta";
"B"
$PN"2"33;
"A"
$PN"1"10;
%"Q_RES"
"1","(-4725,5250)","0","pure_quanta","I19";
;
LOCATION"PR360"
$SEC"1"
CDS_SEC"1"
PACK_TYPE"0402LF"
TOLERANCE"1%"
MATERIAL"CHIP"
WATTAGE"1/16W"
VALUE"4.7"
PART_NUMBER"CS-4702FB19"
CDS_LIB"pure_quanta";
"B"
$PN"2"23;
"A"
$PN"1"17;
%"UNIVERSAL_GND"
"1","(-5450,4175)","0","pure_quanta_power","I2";
;
CDS_LIB"pure_quanta_power"
HDL_POWER"GND";
"A"48;
%"Q_RES"
"1","(-4200,3725)","0","pure_quanta","I22";
;
LOCATION"PR362"
$SEC"1"
CDS_SEC"1"
WATTAGE"1/16W"
MATERIAL"CHIP"
TOLERANCE"5%"
VALUE"0"
PART_NUMBER"CS00002JB38"
PACK_TYPE"0402LF"
CDS_LIB"pure_quanta";
"B"
$PN"2"11;
"A"
$PN"1"55;
%"Q_CAP"
"1","(-5100,5750)","0","pure_quanta","I23";
;
LOCATION"PC585_1"
$SEC"1"
CDS_SEC"1"
MATERIAL"X6S"
TOLERANCE"10%"
VALUE"1UF"
VOLTAGE"25V"
PACK_TYPE"C0402"
PART_NUMBER"CH5104KEB02"
CDS_LIB"pure_quanta";
"B"
$PN"2"16;
"A"
$PN"1"50;
%"Q_CAP"
"1","(-4775,5750)","0","pure_quanta","I24";
;
LOCATION"PC587_1"
$SEC"1"
CDS_SEC"1"
MATERIAL"X6S"
VALUE"10UF"
PART_NUMBER"CH6104KEA00"
VOLTAGE"25V"
PACK_TYPE"C0805"
TOLERANCE"10%"
CDS_LIB"pure_quanta";
"B"
$PN"2"16;
"A"
$PN"1"50;
%"Q_CAP"
"1","(-4450,5750)","0","pure_quanta","I25";
;
LOCATION"PC589_1"
$SEC"1"
CDS_SEC"1"
MATERIAL"X6S"
TOLERANCE"10%"
VALUE"10UF"
PART_NUMBER"CH6104KEA00"
VOLTAGE"25V"
PACK_TYPE"C0805"
CDS_LIB"pure_quanta";
"B"
$PN"2"16;
"A"
$PN"1"50;
%"Q_CAP"
"1","(-4150,5750)","0","pure_quanta","I26";
;
LOCATION"PC591_1"
$SEC"1"
CDS_SEC"1"
MATERIAL"X6S"
TOLERANCE"10%"
VALUE"10UF"
VOLTAGE"25V"
PACK_TYPE"C0805"
PART_NUMBER"CH6104KEA00"
CDS_LIB"pure_quanta";
"B"
$PN"2"16;
"A"
$PN"1"50;
%"Q_CAP"
"1","(-1700,4725)","0","pure_quanta","I29";
;
LOCATION"PC599"
$SEC"1"
CDS_SEC"1"
MATERIAL"X7R"
PART_NUMBER"CH4104K1B00"
PACK_TYPE"0402"
VALUE"0.1UF"
VOLTAGE"25V"
TOLERANCE"10%"
CDS_LIB"pure_quanta";
"B"
$PN"2"20;
"A"
$PN"1"11;
%"UNIVERSAL_GND"
"1","(-3875,5425)","0","pure_quanta_power","I31";
;
CDS_LIB"pure_quanta_power"
HDL_POWER"GND";
"A"16;
%"Q_INDUCTOR"
"1","(-2975,5950)","0","pure_quanta","I34";
;
LOCATION"PL65"
$SEC"1"
CDS_SEC"1"
MATERIAL"IND"
VALUE"50NH/86A"
PART_NUMBER"CVA50^0MZ09"
PACK_TYPE"SMLF"
CDS_LIB"pure_quanta"
NEEDS_NO_SIZE"TRUE";
"1"
$PN"1"50;
"2"
$PN"2"21;
%"VCC_CORE"
"1","(-2675,6025)","0","pure_quanta_power","I35";
;
HDL_POWER"P12V_STBY"
CDS_LIB"pure_quanta_power";
"A"21;
%"Q_CAP"
"1","(-1325,4725)","0","pure_quanta","I37";
;
LOCATION"PC602_1"
$SEC"1"
CDS_SEC"1"
MATERIAL"X6S"
TOLERANCE"20%"
VALUE"22UF"
PART_NUMBER"TMP_QCH622KMEA01"
VOLTAGE"4V"
PACK_TYPE"0805"
CDS_LIB"pure_quanta";
"B"
$PN"2"20;
"A"
$PN"1"11;
%"UNIVERSAL_GND"
"1","(-550,4300)","0","pure_quanta_power","I38";
;
CDS_LIB"pure_quanta_power"
HDL_POWER"GND";
"A"20;
%"Q_CAP"
"1","(-875,4725)","0","pure_quanta","I39";
;
LOCATION"PC604_1"
$SEC"1"
CDS_SEC"1"
MATERIAL"X6S"
TOLERANCE"20%"
VALUE"22UF"
VOLTAGE"4V"
PACK_TYPE"0805"
CDS_LIB"pure_quanta"
PART_NUMBER"TMP_QCH622KMEA01";
"B"
$PN"2"20;
"A"
$PN"1"11;
%"Q_CAP"
"1","(-7850,4625)","0","pure_quanta","I4";
;
LOCATION"PC577_7"
$SEC"1"
CDS_SEC"1"
MATERIAL"X7R"
TOLERANCE"10%"
VALUE"0.1UF"
PART_NUMBER"CH4104K1B00"
VOLTAGE"25V"
PACK_TYPE"0402"
CDS_LIB"pure_quanta";
"B"
$PN"2"8;
"A"
$PN"1"34;
%"VCC_CORE"
"1","(-550,5025)","0","pure_quanta_power","I40";
;
HDL_POWER"PVDDCR_SOC_P0"
CDS_LIB"pure_quanta_power";
"A"11;
%"Q_INDUCTOR4P_14"
"1","(-3100,4775)","0","pure_quanta","I42";
;
LOCATION"PL63"
$SEC"1"
CDS_SEC"1"
PART_NUMBER"CV+15^0TZ04"
PART_TYPE"SMLF"
MATERIAL"IND"
VALUE"150NH"
CDS_LIB"pure_quanta"
NEEDS_NO_SIZE"TRUE";
"1"
$PN"1"18;
"4"
$PN"4"11;
"3"
$PN"3"22;
"2"
$PN"2"24;
%"Q_CAP"
"1","(-3875,5125)","0","pure_quanta","I43";
;
LOCATION"PC593"
$SEC"1"
CDS_SEC"1"
VALUE"0.22UF"
VOLTAGE"16V"
MATERIAL"X7R"
TOLERANCE"10%"
PART_NUMBER"CH4223K1B00"
PACK_TYPE"0402"
CDS_LIB"pure_quanta";
"B"
$PN"2"19;
"A"
$PN"1"23;
%"UNIVERSAL_GND"
"1","(-5425,1100)","0","pure_quanta_power","I46";
;
CDS_LIB"pure_quanta_power"
HDL_POWER"GND";
"A"40;
%"Q_CAP"
"1","(-7825,1525)","0","pure_quanta","I48";
;
LOCATION"PC578_8"
$SEC"1"
CDS_SEC"1"
PACK_TYPE"0402"
VOLTAGE"25V"
PART_NUMBER"CH4104K1B00"
TOLERANCE"10%"
MATERIAL"X7R"
VALUE"0.1UF"
CDS_LIB"pure_quanta";
"B"
$PN"2"7;
"A"
$PN"1"46;
%"UNIVERSAL_GND"
"1","(-7825,1250)","0","pure_quanta_power","I49";
;
CDS_LIB"pure_quanta_power"
HDL_POWER"GND";
"A"7;
%"UNIVERSAL_GND"
"1","(-7850,4350)","0","pure_quanta_power","I5";
;
CDS_LIB"pure_quanta_power"
HDL_POWER"GND";
"A"8;
%"UNIVERSAL_GND"
"1","(-7500,1325)","0","pure_quanta_power","I50";
;
CDS_LIB"pure_quanta_power"
HDL_POWER"GND";
"A"9;
%"Q_RES"
"1","(-7150,1500)","0","pure_quanta","I52";
;
LOCATION"PR359"
$SEC"1"
CDS_SEC"1"
WATTAGE"1/16W"
MATERIAL"EMPTY"
PART_NUMBER"CS28872FB01"
PACK_TYPE"0402LF"
VALUE"8.87K"
TOLERANCE"1%"
CDS_LIB"pure_quanta";
"B"
$PN"2"45;
"A"
$PN"1"9;
%"UNIVERSAL_GND"
"1","(-7525,4425)","0","pure_quanta_power","I6";
;
CDS_LIB"pure_quanta_power"
HDL_POWER"GND";
"A"10;
%"Q_RES"
"1","(-4675,2150)","0","pure_quanta","I63";
;
LOCATION"PR361"
$SEC"1"
CDS_SEC"1"
PACK_TYPE"0402LF"
TOLERANCE"1%"
MATERIAL"CHIP"
WATTAGE"1/16W"
VALUE"4.7"
PART_NUMBER"CS-4702FB19"
CDS_LIB"pure_quanta";
"B"
$PN"2"51;
"A"
$PN"1"36;
%"Q_RES"
"1","(-4225,800)","0","pure_quanta","I65";
;
LOCATION"PR363"
$SEC"1"
CDS_SEC"1"
WATTAGE"1/16W"
TOLERANCE"5%"
MATERIAL"CHIP"
VALUE"0"
PART_NUMBER"CS00002JB38"
PACK_TYPE"0402LF"
CDS_LIB"pure_quanta";
"B"
$PN"2"58;
"A"
$PN"1"57;
%"Q_CAP"
"1","(-3775,2025)","0","pure_quanta","I66";
;
LOCATION"PC594"
$SEC"1"
CDS_SEC"1"
PACK_TYPE"0402"
PART_NUMBER"CH4223K1B00"
MATERIAL"X7R"
TOLERANCE"10%"
VALUE"0.22UF"
VOLTAGE"16V"
CDS_LIB"pure_quanta";
"B"
$PN"2"14;
"A"
$PN"1"51;
%"Q_CAP"
"1","(-4975,2700)","0","pure_quanta","I67";
;
LOCATION"PC586_2"
$SEC"1"
CDS_SEC"1"
MATERIAL"X6S"
TOLERANCE"10%"
VALUE"1UF"
PART_NUMBER"CH5104KEB02"
PACK_TYPE"C0402"
VOLTAGE"25V"
CDS_LIB"pure_quanta";
"B"
$PN"2"56;
"A"
$PN"1"12;
%"Q_CAP"
"1","(-4650,2700)","0","pure_quanta","I68";
;
LOCATION"PC588_2"
$SEC"1"
CDS_SEC"1"
MATERIAL"X6S"
TOLERANCE"10%"
VALUE"10UF"
PART_NUMBER"CH6104KEA00"
VOLTAGE"25V"
PACK_TYPE"C0805"
CDS_LIB"pure_quanta";
"B"
$PN"2"56;
"A"
$PN"1"12;
%"Q_CAP"
"1","(-4325,2700)","0","pure_quanta","I69";
;
LOCATION"PC590_2"
$SEC"1"
CDS_SEC"1"
MATERIAL"X6S"
TOLERANCE"10%"
VALUE"10UF"
PART_NUMBER"CH6104KEA00"
VOLTAGE"25V"
PACK_TYPE"C0805"
CDS_LIB"pure_quanta";
"B"
$PN"2"56;
"A"
$PN"1"12;
%"Q_CAP"
"1","(-4000,2700)","0","pure_quanta","I70";
;
LOCATION"PC592_2"
$SEC"1"
CDS_SEC"1"
PART_NUMBER"CH6104KEA00"
PACK_TYPE"C0805"
MATERIAL"X6S"
TOLERANCE"10%"
VALUE"10UF"
VOLTAGE"25V"
CDS_LIB"pure_quanta";
"B"
$PN"2"56;
"A"
$PN"1"12;
%"UNIVERSAL_GND"
"1","(-3600,2375)","0","pure_quanta_power","I71";
;
CDS_LIB"pure_quanta_power"
HDL_POWER"GND";
"A"56;
%"VCC_CORE"
"1","(-3600,2975)","0","pure_quanta_power","I73";
;
HDL_POWER"SW_P12V_STBY_PVDDCR_SOC_P0_FLT"
CDS_LIB"pure_quanta_power";
"A"12;
%"Q_CAP"
"1","(-1625,1625)","0","pure_quanta","I79";
;
LOCATION"PC600_2"
$SEC"1"
CDS_SEC"1"
MATERIAL"X6S"
TOLERANCE"20%"
VALUE"22UF"
PART_NUMBER"TMP_QCH622KMEA01"
VOLTAGE"4V"
PACK_TYPE"0805"
CDS_LIB"pure_quanta";
"B"
$PN"2"26;
"A"
$PN"1"58;
%"UNIVERSAL_GND"
"1","(-1200,1275)","0","pure_quanta_power","I80";
;
CDS_LIB"pure_quanta_power"
HDL_POWER"GND";
"A"26;
%"Q_CAP"
"1","(-1200,1625)","0","pure_quanta","I81";
;
LOCATION"PC603_2"
$SEC"1"
CDS_SEC"1"
MATERIAL"X6S"
TOLERANCE"20%"
VALUE"22UF"
PART_NUMBER"TMP_QCH622KMEA01"
VOLTAGE"4V"
PACK_TYPE"0805"
CDS_LIB"pure_quanta";
"B"
$PN"2"26;
"A"
$PN"1"58;
%"VCC_CORE"
"1","(-1200,1950)","0","pure_quanta_power","I82";
;
HDL_POWER"PVDDCR_SOC_P0"
CDS_LIB"pure_quanta_power";
"A"58;
%"Q_INDUCTOR4P_14"
"1","(-3025,1675)","0","pure_quanta","I83";
;
LOCATION"PL64"
$SEC"1"
CDS_SEC"1"
PART_TYPE"SMLF"
MATERIAL"IND"
VALUE"150NH"
PART_NUMBER"CV+15^0TZ04"
CDS_LIB"pure_quanta"
NEEDS_NO_SIZE"TRUE";
"1"
$PN"1"15;
"4"
$PN"4"58;
"3"
$PN"3"27;
"2"
$PN"2"28;
%"Q_CAPP"
"1","(-1825,3075)","0","pure_quanta","I92";
;
LOCATION"PC597"
$SEC"1"
CDS_SEC"1"
VALUE"470UF"
MATERIAL"EMPTY"
TOLERANCE"20%"
PART_NUMBER"CH747LM8825"
VOLTAGE"2.5V"
PACK_TYPE"SMLF"
CDS_LIB"pure_quanta";
"A"
$PN"1"25;
"B"
$PN"2"59;
%"Q_CAPP"
"1","(-1475,3075)","0","pure_quanta","I94";
;
LOCATION"PC598"
$SEC"1"
CDS_SEC"1"
PART_NUMBER"CH747LM8825"
PACK_TYPE"SMLF"
MATERIAL"SPCAP"
TOLERANCE"20%"
VOLTAGE"2.5V"
VALUE"470UF"
CDS_LIB"pure_quanta";
"A"
$PN"1"25;
"B"
$PN"2"59;
END.
